(kicad_pcb
	(version 20260206)
	(generator "pcbnew")
	(generator_version "10.0")
	(general
		(thickness 1.6)
		(legacy_teardrops no)
	)
	(paper "A4")
	(title_block
		(title "04192023_DAF0TMB3IC0_F0TG_MB_C_brd_V02_OCP.brd")
		(comment 1 "Grand Teton / footprints 4718-4722 of 8354")
	)
	(layers
		(0 "F.Cu" signal "TOP")
		(4 "In1.Cu" signal "GND")
		(6 "In2.Cu" signal "IN1")
		(8 "In3.Cu" signal "GND1")
		(10 "In4.Cu" signal "IN2")
		(12 "In5.Cu" signal "GND2")
		(14 "In6.Cu" signal "IN3")
		(16 "In7.Cu" signal "GND3")
		(18 "In8.Cu" signal "VCC")
		(20 "In9.Cu" signal "VCC1")
		(22 "In10.Cu" signal "GND4")
		(24 "In11.Cu" signal "IN4")
		(26 "In12.Cu" signal "GND5")
		(28 "In13.Cu" signal "IN5")
		(30 "In14.Cu" signal "GND6")
		(32 "In15.Cu" signal "IN6")
		(34 "In16.Cu" signal "GND7")
		(2 "B.Cu" signal "BOTTOM")
		(9 "F.Adhes" user "F.Adhesive")
		(11 "B.Adhes" user "B.Adhesive")
		(13 "F.Paste" user "Package Geometry/Pastemask Top")
		(15 "B.Paste" user "Package Geometry/Pastemask Bottom")
		(5 "F.SilkS" user "Ref Des/Silkscreen Top")
		(7 "B.SilkS" user "Ref Des/Silkscreen Bottom")
		(1 "F.Mask" user "Board Geometry/Soldermask Top")
		(3 "B.Mask" user "Board Geometry/Soldermask Bottom")
		(17 "Dwgs.User" user "User.Drawings")
		(19 "Cmts.User" user "User.Comments")
		(21 "Eco1.User" user "User.Eco1")
		(23 "Eco2.User" user "User.Eco2")
		(25 "Edge.Cuts" user "Board Geometry/Outline")
		(27 "Margin" user)
		(31 "F.CrtYd" user "Package Geometry/Place Bound Top")
		(29 "B.CrtYd" user "Package Geometry/Place Bound Bottom")
		(35 "F.Fab" user "Ref Des/Assembly Top")
		(33 "B.Fab" user "Ref Des/Assembly Bottom")
	)
	(footprint ""
		(layer "F.Cu")
		(at 186.804046 -94.876112 -90)
		(property "Reference" "R397"
			(at 0 0 270)
			(layer "F.SilkS")
			(hide yes)
			(effects
				(font
					(size 1.27 1.27)
				)
			)
		)
		(property "Value" ""
			(at 0 0 270)
			(layer "F.Fab")
			(effects
				(font
					(size 1.27 1.27)
				)
			)
		)
		(duplicate_pad_numbers_are_jumpers no)
		(fp_line
			(start -0.7874 0.4064)
			(end -0.7874 -0.4064)
			(stroke
				(width 0.1524)
				(type default)
			)
			(layer "F.SilkS")
		)
		(fp_line
			(start 0.7874 0.4064)
			(end -0.7874 0.4064)
			(stroke
				(width 0.1524)
				(type default)
			)
			(layer "F.SilkS")
		)
		(fp_line
			(start -0.7874 -0.4064)
			(end 0.7874 -0.4064)
			(stroke
				(width 0.1524)
				(type default)
			)
			(layer "F.SilkS")
		)
		(fp_line
			(start 0.7874 -0.4064)
			(end 0.7874 0.4064)
			(stroke
				(width 0.1524)
				(type default)
			)
			(layer "F.SilkS")
		)
		(fp_line
			(start -0.67945 0.3048)
			(end -0.67945 -0.305054)
			(stroke
				(width 0.1)
				(type default)
			)
			(layer "F.Fab")
		)
		(fp_line
			(start -0.12065 0.3048)
			(end -0.67945 0.3048)
			(stroke
				(width 0.1)
				(type default)
			)
			(layer "F.Fab")
		)
		(fp_line
			(start 0.120396 0.3048)
			(end 0.120396 0.2794)
			(stroke
				(width 0.1)
				(type default)
			)
			(layer "F.Fab")
		)
		(fp_line
			(start 0.67945 0.3048)
			(end 0.120396 0.3048)
			(stroke
				(width 0.1)
				(type default)
			)
			(layer "F.Fab")
		)
		(fp_line
			(start -0.12065 0.2794)
			(end -0.12065 0.3048)
			(stroke
				(width 0.1)
				(type default)
			)
			(layer "F.Fab")
		)
		(fp_line
			(start 0.120396 0.2794)
			(end -0.12065 0.2794)
			(stroke
				(width 0.1)
				(type default)
			)
			(layer "F.Fab")
		)
		(fp_line
			(start -0.12065 -0.2794)
			(end 0.12065 -0.2794)
			(stroke
				(width 0.1)
				(type default)
			)
			(layer "F.Fab")
		)
		(fp_line
			(start 0.12065 -0.2794)
			(end 0.12065 -0.3048)
			(stroke
				(width 0.1)
				(type default)
			)
			(layer "F.Fab")
		)
		(fp_line
			(start 0.12065 -0.3048)
			(end 0.67945 -0.3048)
			(stroke
				(width 0.1)
				(type default)
			)
			(layer "F.Fab")
		)
		(fp_line
			(start 0.67945 -0.3048)
			(end 0.67945 0.3048)
			(stroke
				(width 0.1)
				(type default)
			)
			(layer "F.Fab")
		)
		(fp_line
			(start -0.67945 -0.305054)
			(end -0.12065 -0.305054)
			(stroke
				(width 0.1)
				(type default)
			)
			(layer "F.Fab")
		)
		(fp_line
			(start -0.12065 -0.305054)
			(end -0.12065 -0.2794)
			(stroke
				(width 0.1)
				(type default)
			)
			(layer "F.Fab")
		)
		(pad "1" smd circle
			(at -0.40005 0 270)
			(size 0 0)
			(layers "F.Cu" "F.Mask" "F.Paste")
			(net "P3V3_AUX")
		)
		(pad "2" smd circle
			(at 0.40005 0 270)
			(size 0 0)
			(layers "F.Cu" "F.Mask" "F.Paste")
			(net "CPU0_SP5R1")
		)
	)
	(footprint ""
		(layer "F.Cu")
		(at 259.89788 -47.650146 90)
		(property "Reference" "PC2198"
			(at 0 0 90)
			(layer "F.SilkS")
			(hide yes)
			(effects
				(font
					(size 1.27 1.27)
				)
			)
		)
		(property "Value" ""
			(at 0 0 90)
			(layer "F.Fab")
			(effects
				(font
					(size 1.27 1.27)
				)
			)
		)
		(duplicate_pad_numbers_are_jumpers no)
		(fp_line
			(start 0.7874 -0.4064)
			(end 0.7874 0.4064)
			(stroke
				(width 0.1524)
				(type default)
			)
			(layer "F.SilkS")
		)
		(fp_line
			(start -0.7874 -0.4064)
			(end 0.7874 -0.4064)
			(stroke
				(width 0.1524)
				(type default)
			)
			(layer "F.SilkS")
		)
		(fp_line
			(start 0.7874 0.4064)
			(end -0.7874 0.4064)
			(stroke
				(width 0.1524)
				(type default)
			)
			(layer "F.SilkS")
		)
		(fp_line
			(start -0.7874 0.4064)
			(end -0.7874 -0.4064)
			(stroke
				(width 0.1524)
				(type default)
			)
			(layer "F.SilkS")
		)
		(fp_line
			(start -0.12065 -0.305054)
			(end -0.12065 -0.2794)
			(stroke
				(width 0.1)
				(type default)
			)
			(layer "F.Fab")
		)
		(fp_line
			(start -0.67945 -0.305054)
			(end -0.12065 -0.305054)
			(stroke
				(width 0.1)
				(type default)
			)
			(layer "F.Fab")
		)
		(fp_line
			(start 0.67945 -0.3048)
			(end 0.67945 0.3048)
			(stroke
				(width 0.1)
				(type default)
			)
			(layer "F.Fab")
		)
		(fp_line
			(start 0.12065 -0.3048)
			(end 0.67945 -0.3048)
			(stroke
				(width 0.1)
				(type default)
			)
			(layer "F.Fab")
		)
		(fp_line
			(start 0.12065 -0.2794)
			(end 0.12065 -0.3048)
			(stroke
				(width 0.1)
				(type default)
			)
			(layer "F.Fab")
		)
		(fp_line
			(start -0.12065 -0.2794)
			(end 0.12065 -0.2794)
			(stroke
				(width 0.1)
				(type default)
			)
			(layer "F.Fab")
		)
		(fp_line
			(start 0.120396 0.2794)
			(end -0.12065 0.2794)
			(stroke
				(width 0.1)
				(type default)
			)
			(layer "F.Fab")
		)
		(fp_line
			(start -0.12065 0.2794)
			(end -0.12065 0.3048)
			(stroke
				(width 0.1)
				(type default)
			)
			(layer "F.Fab")
		)
		(fp_line
			(start 0.67945 0.3048)
			(end 0.120396 0.3048)
			(stroke
				(width 0.1)
				(type default)
			)
			(layer "F.Fab")
		)
		(fp_line
			(start 0.120396 0.3048)
			(end 0.120396 0.2794)
			(stroke
				(width 0.1)
				(type default)
			)
			(layer "F.Fab")
		)
		(fp_line
			(start -0.12065 0.3048)
			(end -0.67945 0.3048)
			(stroke
				(width 0.1)
				(type default)
			)
			(layer "F.Fab")
		)
		(fp_line
			(start -0.67945 0.3048)
			(end -0.67945 -0.305054)
			(stroke
				(width 0.1)
				(type default)
			)
			(layer "F.Fab")
		)
		(pad "1" smd circle
			(at -0.40005 0 90)
			(size 0 0)
			(layers "F.Cu" "F.Mask" "F.Paste")
			(net "P12V_AUX")
		)
		(pad "2" smd circle
			(at 0.40005 0 90)
			(size 0 0)
			(layers "F.Cu" "F.Mask" "F.Paste")
			(net "GND")
		)
	)
	(footprint ""
		(layer "F.Cu")
		(at 4.747514 -44.106592 90)
		(property "Reference" "R932"
			(at 0 0 90)
			(layer "F.SilkS")
			(hide yes)
			(effects
				(font
					(size 1.27 1.27)
				)
			)
		)
		(property "Value" ""
			(at 0 0 90)
			(layer "F.Fab")
			(effects
				(font
					(size 1.27 1.27)
				)
			)
		)
		(duplicate_pad_numbers_are_jumpers no)
		(fp_line
			(start 0.7874 -0.4064)
			(end 0.7874 0.4064)
			(stroke
				(width 0.1524)
				(type default)
			)
			(layer "F.SilkS")
		)
		(fp_line
			(start -0.7874 -0.4064)
			(end 0.7874 -0.4064)
			(stroke
				(width 0.1524)
				(type default)
			)
			(layer "F.SilkS")
		)
		(fp_line
			(start 0.7874 0.4064)
			(end -0.7874 0.4064)
			(stroke
				(width 0.1524)
				(type default)
			)
			(layer "F.SilkS")
		)
		(fp_line
			(start -0.7874 0.4064)
			(end -0.7874 -0.4064)
			(stroke
				(width 0.1524)
				(type default)
			)
			(layer "F.SilkS")
		)
		(fp_line
			(start -0.12065 -0.305054)
			(end -0.12065 -0.2794)
			(stroke
				(width 0.1)
				(type default)
			)
			(layer "F.Fab")
		)
		(fp_line
			(start -0.67945 -0.305054)
			(end -0.12065 -0.305054)
			(stroke
				(width 0.1)
				(type default)
			)
			(layer "F.Fab")
		)
		(fp_line
			(start 0.67945 -0.3048)
			(end 0.67945 0.3048)
			(stroke
				(width 0.1)
				(type default)
			)
			(layer "F.Fab")
		)
		(fp_line
			(start 0.12065 -0.3048)
			(end 0.67945 -0.3048)
			(stroke
				(width 0.1)
				(type default)
			)
			(layer "F.Fab")
		)
		(fp_line
			(start 0.12065 -0.2794)
			(end 0.12065 -0.3048)
			(stroke
				(width 0.1)
				(type default)
			)
			(layer "F.Fab")
		)
		(fp_line
			(start -0.12065 -0.2794)
			(end 0.12065 -0.2794)
			(stroke
				(width 0.1)
				(type default)
			)
			(layer "F.Fab")
		)
		(fp_line
			(start 0.120396 0.2794)
			(end -0.12065 0.2794)
			(stroke
				(width 0.1)
				(type default)
			)
			(layer "F.Fab")
		)
		(fp_line
			(start -0.12065 0.2794)
			(end -0.12065 0.3048)
			(stroke
				(width 0.1)
				(type default)
			)
			(layer "F.Fab")
		)
		(fp_line
			(start 0.67945 0.3048)
			(end 0.120396 0.3048)
			(stroke
				(width 0.1)
				(type default)
			)
			(layer "F.Fab")
		)
		(fp_line
			(start 0.120396 0.3048)
			(end 0.120396 0.2794)
			(stroke
				(width 0.1)
				(type default)
			)
			(layer "F.Fab")
		)
		(fp_line
			(start -0.12065 0.3048)
			(end -0.67945 0.3048)
			(stroke
				(width 0.1)
				(type default)
			)
			(layer "F.Fab")
		)
		(fp_line
			(start -0.67945 0.3048)
			(end -0.67945 -0.305054)
			(stroke
				(width 0.1)
				(type default)
			)
			(layer "F.Fab")
		)
		(pad "1" smd circle
			(at -0.40005 0 90)
			(size 0 0)
			(layers "F.Cu" "F.Mask" "F.Paste")
			(net "CPU1_XTRIG_L7")
		)
		(pad "2" smd circle
			(at 0.40005 0 90)
			(size 0 0)
			(layers "F.Cu" "F.Mask" "F.Paste")
			(net "CPU1_XTRIG_R1_L7")
		)
	)
	(footprint ""
		(layer "F.Cu")
		(at 117.895624 -260.305296 180)
		(property "Reference" "C2286"
			(at 0 0 180)
			(layer "F.SilkS")
			(hide yes)
			(effects
				(font
					(size 1.27 1.27)
				)
			)
		)
		(property "Value" ""
			(at 0 0 180)
			(layer "F.Fab")
			(effects
				(font
					(size 1.27 1.27)
				)
			)
		)
		(duplicate_pad_numbers_are_jumpers no)
		(fp_line
			(start 0.7874 0.4064)
			(end -0.7874 0.4064)
			(stroke
				(width 0.1524)
				(type default)
			)
			(layer "F.SilkS")
		)
		(fp_line
			(start 0.7874 -0.4064)
			(end 0.7874 0.4064)
			(stroke
				(width 0.1524)
				(type default)
			)
			(layer "F.SilkS")
		)
		(fp_line
			(start -0.7874 0.4064)
			(end -0.7874 -0.4064)
			(stroke
				(width 0.1524)
				(type default)
			)
			(layer "F.SilkS")
		)
		(fp_line
			(start -0.7874 -0.4064)
			(end 0.7874 -0.4064)
			(stroke
				(width 0.1524)
				(type default)
			)
			(layer "F.SilkS")
		)
		(fp_line
			(start 0.67945 0.3048)
			(end 0.120396 0.3048)
			(stroke
				(width 0.1)
				(type default)
			)
			(layer "F.Fab")
		)
		(fp_line
			(start 0.67945 -0.3048)
			(end 0.67945 0.3048)
			(stroke
				(width 0.1)
				(type default)
			)
			(layer "F.Fab")
		)
		(fp_line
			(start 0.12065 -0.2794)
			(end 0.12065 -0.3048)
			(stroke
				(width 0.1)
				(type default)
			)
			(layer "F.Fab")
		)
		(fp_line
			(start 0.12065 -0.3048)
			(end 0.67945 -0.3048)
			(stroke
				(width 0.1)
				(type default)
			)
			(layer "F.Fab")
		)
		(fp_line
			(start 0.120396 0.3048)
			(end 0.120396 0.2794)
			(stroke
				(width 0.1)
				(type default)
			)
			(layer "F.Fab")
		)
		(fp_line
			(start 0.120396 0.2794)
			(end -0.12065 0.2794)
			(stroke
				(width 0.1)
				(type default)
			)
			(layer "F.Fab")
		)
		(fp_line
			(start -0.12065 0.3048)
			(end -0.67945 0.3048)
			(stroke
				(width 0.1)
				(type default)
			)
			(layer "F.Fab")
		)
		(fp_line
			(start -0.12065 0.2794)
			(end -0.12065 0.3048)
			(stroke
				(width 0.1)
				(type default)
			)
			(layer "F.Fab")
		)
		(fp_line
			(start -0.12065 -0.2794)
			(end 0.12065 -0.2794)
			(stroke
				(width 0.1)
				(type default)
			)
			(layer "F.Fab")
		)
		(fp_line
			(start -0.12065 -0.305054)
			(end -0.12065 -0.2794)
			(stroke
				(width 0.1)
				(type default)
			)
			(layer "F.Fab")
		)
		(fp_line
			(start -0.67945 0.3048)
			(end -0.67945 -0.305054)
			(stroke
				(width 0.1)
				(type default)
			)
			(layer "F.Fab")
		)
		(fp_line
			(start -0.67945 -0.305054)
			(end -0.12065 -0.305054)
			(stroke
				(width 0.1)
				(type default)
			)
			(layer "F.Fab")
		)
		(pad "1" smd circle
			(at -0.40005 0 180)
			(size 0 0)
			(layers "F.Cu" "F.Mask" "F.Paste")
			(net "PVDDCR_SOC_P1")
		)
		(pad "2" smd circle
			(at 0.40005 0 180)
			(size 0 0)
			(layers "F.Cu" "F.Mask" "F.Paste")
			(net "GND")
		)
	)
	(footprint ""
		(layer "F.Cu")
		(at 245.589298 -242.048538)
		(property "Reference" "ME11"
			(at 0 0 0)
			(layer "F.SilkS")
			(hide yes)
			(effects
				(font
					(size 1.27 1.27)
				)
			)
		)
		(property "Value" ""
			(at 0 0 0)
			(layer "F.Fab")
			(effects
				(font
					(size 1.27 1.27)
				)
			)
		)
		(duplicate_pad_numbers_are_jumpers no)
		(zone
			(layer "F.Cu")
			(hatch none 0.5)
			(connect_pads
				(clearance 0)
			)
			(min_thickness 0.25)
			(keepout
				(tracks allowed)
				(vias allowed)
				(pads allowed)
				(copperpour allowed)
				(footprints not_allowed)
			)
			(placement
				(enabled no)
				(sheetname "")
			)
			(fill
				(thermal_gap 0.5)
				(thermal_bridge_width 0.5)
				(island_removal_mode 0)
			)
			(polygon
				(pts
					(arc
						(start 255.589278 -242.048538)
						(mid 235.589318 -242.048538)
						(end 255.589278 -242.048538)
					)
				)
			)
		)
	)
)
